# T6G (Grand Teton) — schematic netlist excerpt (pin names and nets, part order shuffled) for the footprints in the layout excerpt that follows; sources: Cadence DE-HDL packaged netlist, KiCad conversion of 04192023_DAF0TMB3IC0_F0TG_MB_C_brd_V02_OCP.brd

R13  Q_RES  0 5% CHIP  pkg 0402LF  page 85 : A = JTAG_PLD_TDO ; B = JTAG_SCM_PLD_TDO
C1030  Q_CAP  22UF 4V 20% X6S  pkg C0402  page 312 : A = P0V9_CPU0_RT3_2A ; B = GND

(kicad_pcb
	(version 20260206)
	(generator "pcbnew")
	(generator_version "10.0")
	(general
		(thickness 1.6)
		(legacy_teardrops no)
	)
	(paper "A4")
	(title_block
		(title "04192023_DAF0TMB3IC0_F0TG_MB_C_brd_V02_OCP.brd")
		(comment 1 "Grand Teton / footprints 5471-5472 of 8354")
	)
	(layers
		(0 "F.Cu" signal "TOP")
		(4 "In1.Cu" signal "GND")
		(6 "In2.Cu" signal "IN1")
		(8 "In3.Cu" signal "GND1")
		(10 "In4.Cu" signal "IN2")
		(12 "In5.Cu" signal "GND2")
		(14 "In6.Cu" signal "IN3")
		(16 "In7.Cu" signal "GND3")
		(18 "In8.Cu" signal "VCC")
		(20 "In9.Cu" signal "VCC1")
		(22 "In10.Cu" signal "GND4")
		(24 "In11.Cu" signal "IN4")
		(26 "In12.Cu" signal "GND5")
		(28 "In13.Cu" signal "IN5")
		(30 "In14.Cu" signal "GND6")
		(32 "In15.Cu" signal "IN6")
		(34 "In16.Cu" signal "GND7")
		(2 "B.Cu" signal "BOTTOM")
		(9 "F.Adhes" user "F.Adhesive")
		(11 "B.Adhes" user "B.Adhesive")
		(13 "F.Paste" user "Package Geometry/Pastemask Top")
		(15 "B.Paste" user "Package Geometry/Pastemask Bottom")
		(5 "F.SilkS" user "Ref Des/Silkscreen Top")
		(7 "B.SilkS" user "Ref Des/Silkscreen Bottom")
		(1 "F.Mask" user "Board Geometry/Soldermask Top")
		(3 "B.Mask" user "Board Geometry/Soldermask Bottom")
		(17 "Dwgs.User" user "User.Drawings")
		(19 "Cmts.User" user "User.Comments")
		(21 "Eco1.User" user "User.Eco1")
		(23 "Eco2.User" user "User.Eco2")
		(25 "Edge.Cuts" user "Board Geometry/Outline")
		(27 "Margin" user)
		(31 "F.CrtYd" user "Package Geometry/Place Bound Top")
		(29 "B.CrtYd" user "Package Geometry/Place Bound Bottom")
		(35 "F.Fab" user "Ref Des/Assembly Top")
		(33 "B.Fab" user "Ref Des/Assembly Bottom")
	)
	(footprint ""
		(layer "B.Cu")
		(at 149.597872 -64.04229 90)
		(property "Reference" "R13"
			(at 0 0 90)
			(layer "B.SilkS")
			(hide yes)
			(effects
				(font
					(size 1.27 1.27)
				)
				(justify mirror)
			)
		)
		(property "Value" ""
			(at 0 0 90)
			(layer "B.Fab")
			(effects
				(font
					(size 1.27 1.27)
				)
				(justify mirror)
			)
		)
		(duplicate_pad_numbers_are_jumpers no)
		(fp_line
			(start 0.7874 -0.4064)
			(end -0.7874 -0.4064)
			(stroke
				(width 0.1524)
				(type default)
			)
			(layer "B.SilkS")
		)
		(fp_line
			(start -0.7874 -0.4064)
			(end -0.7874 0.4064)
			(stroke
				(width 0.1524)
				(type default)
			)
			(layer "B.SilkS")
		)
		(fp_line
			(start 0.7874 0.4064)
			(end 0.7874 -0.4064)
			(stroke
				(width 0.1524)
				(type default)
			)
			(layer "B.SilkS")
		)
		(fp_line
			(start -0.7874 0.4064)
			(end 0.7874 0.4064)
			(stroke
				(width 0.1524)
				(type default)
			)
			(layer "B.SilkS")
		)
		(fp_line
			(start 0.67945 -0.305054)
			(end 0.12065 -0.305054)
			(stroke
				(width 0.1)
				(type default)
			)
			(layer "B.Fab")
		)
		(fp_line
			(start 0.12065 -0.305054)
			(end 0.12065 -0.2794)
			(stroke
				(width 0.1)
				(type default)
			)
			(layer "B.Fab")
		)
		(fp_line
			(start -0.12065 -0.3048)
			(end -0.67945 -0.3048)
			(stroke
				(width 0.1)
				(type default)
			)
			(layer "B.Fab")
		)
		(fp_line
			(start -0.67945 -0.3048)
			(end -0.67945 0.3048)
			(stroke
				(width 0.1)
				(type default)
			)
			(layer "B.Fab")
		)
		(fp_line
			(start 0.12065 -0.2794)
			(end -0.12065 -0.2794)
			(stroke
				(width 0.1)
				(type default)
			)
			(layer "B.Fab")
		)
		(fp_line
			(start -0.12065 -0.2794)
			(end -0.12065 -0.3048)
			(stroke
				(width 0.1)
				(type default)
			)
			(layer "B.Fab")
		)
		(fp_line
			(start 0.12065 0.2794)
			(end 0.12065 0.3048)
			(stroke
				(width 0.1)
				(type default)
			)
			(layer "B.Fab")
		)
		(fp_line
			(start -0.120396 0.2794)
			(end 0.12065 0.2794)
			(stroke
				(width 0.1)
				(type default)
			)
			(layer "B.Fab")
		)
		(fp_line
			(start 0.67945 0.3048)
			(end 0.67945 -0.305054)
			(stroke
				(width 0.1)
				(type default)
			)
			(layer "B.Fab")
		)
		(fp_line
			(start 0.12065 0.3048)
			(end 0.67945 0.3048)
			(stroke
				(width 0.1)
				(type default)
			)
			(layer "B.Fab")
		)
		(fp_line
			(start -0.120396 0.3048)
			(end -0.120396 0.2794)
			(stroke
				(width 0.1)
				(type default)
			)
			(layer "B.Fab")
		)
		(fp_line
			(start -0.67945 0.3048)
			(end -0.120396 0.3048)
			(stroke
				(width 0.1)
				(type default)
			)
			(layer "B.Fab")
		)
		(pad "1" smd circle
			(at 0.40005 0 270)
			(size 0 0)
			(layers "B.Cu" "B.Mask" "B.Paste")
			(net "JTAG_PLD_TDO")
		)
		(pad "2" smd circle
			(at -0.40005 0 270)
			(size 0 0)
			(layers "B.Cu" "B.Mask" "B.Paste")
			(net "JTAG_SCM_PLD_TDO")
		)
	)
	(footprint ""
		(layer "B.Cu")
		(at 371.691154 -398.942052 90)
		(property "Reference" "C1030"
			(at 0 0 90)
			(layer "B.SilkS")
			(hide yes)
			(effects
				(font
					(size 1.27 1.27)
				)
				(justify mirror)
			)
		)
		(property "Value" ""
			(at 0 0 90)
			(layer "B.Fab")
			(effects
				(font
					(size 1.27 1.27)
				)
				(justify mirror)
			)
		)
		(duplicate_pad_numbers_are_jumpers no)
		(fp_line
			(start 0.7874 -0.4064)
			(end -0.7874 -0.4064)
			(stroke
				(width 0.1524)
				(type default)
			)
			(layer "B.SilkS")
		)
		(fp_line
			(start -0.7874 -0.4064)
			(end -0.7874 0.4064)
			(stroke
				(width 0.1524)
				(type default)
			)
			(layer "B.SilkS")
		)
		(fp_line
			(start 0.7874 0.4064)
			(end 0.7874 -0.4064)
			(stroke
				(width 0.1524)
				(type default)
			)
			(layer "B.SilkS")
		)
		(fp_line
			(start -0.7874 0.4064)
			(end 0.7874 0.4064)
			(stroke
				(width 0.1524)
				(type default)
			)
			(layer "B.SilkS")
		)
		(fp_line
			(start 0.67945 -0.305054)
			(end 0.12065 -0.305054)
			(stroke
				(width 0.1)
				(type default)
			)
			(layer "B.Fab")
		)
		(fp_line
			(start 0.12065 -0.305054)
			(end 0.12065 -0.2794)
			(stroke
				(width 0.1)
				(type default)
			)
			(layer "B.Fab")
		)
		(fp_line
			(start -0.12065 -0.3048)
			(end -0.67945 -0.3048)
			(stroke
				(width 0.1)
				(type default)
			)
			(layer "B.Fab")
		)
		(fp_line
			(start -0.67945 -0.3048)
			(end -0.67945 0.3048)
			(stroke
				(width 0.1)
				(type default)
			)
			(layer "B.Fab")
		)
		(fp_line
			(start 0.12065 -0.2794)
			(end -0.12065 -0.2794)
			(stroke
				(width 0.1)
				(type default)
			)
			(layer "B.Fab")
		)
		(fp_line
			(start -0.12065 -0.2794)
			(end -0.12065 -0.3048)
			(stroke
				(width 0.1)
				(type default)
			)
			(layer "B.Fab")
		)
		(fp_line
			(start 0.12065 0.2794)
			(end 0.12065 0.3048)
			(stroke
				(width 0.1)
				(type default)
			)
			(layer "B.Fab")
		)
		(fp_line
			(start -0.120396 0.2794)
			(end 0.12065 0.2794)
			(stroke
				(width 0.1)
				(type default)
			)
			(layer "B.Fab")
		)
		(fp_line
			(start 0.67945 0.3048)
			(end 0.67945 -0.305054)
			(stroke
				(width 0.1)
				(type default)
			)
			(layer "B.Fab")
		)
		(fp_line
			(start 0.12065 0.3048)
			(end 0.67945 0.3048)
			(stroke
				(width 0.1)
				(type default)
			)
			(layer "B.Fab")
		)
		(fp_line
			(start -0.120396 0.3048)
			(end -0.120396 0.2794)
			(stroke
				(width 0.1)
				(type default)
			)
			(layer "B.Fab")
		)
		(fp_line
			(start -0.67945 0.3048)
			(end -0.120396 0.3048)
			(stroke
				(width 0.1)
				(type default)
			)
			(layer "B.Fab")
		)
		(pad "1" smd circle
			(at 0.40005 0 270)
			(size 0 0)
			(layers "B.Cu" "B.Mask" "B.Paste")
			(net "P0V9_CPU0_RT3_2A")
		)
		(pad "2" smd circle
			(at -0.40005 0 270)
			(size 0 0)
			(layers "B.Cu" "B.Mask" "B.Paste")
			(net "GND")
		)
	)
)
